#ISCELL
  mstr_misc dns *
  *
#ISCELL
  pure_quanta quanta_title_block_c *
  *
#ISCELL
  standard offpage *
  page190_i1
#ISCELL
  standard offpage *
  page190_i10
#ISCELL
  pure_quanta_power vcc_core *
  page190_i102
#ISCELL
  pure_quanta_power vcc_core *
  page190_i104
#ISCELL
  pure_quanta_power universal_gnd *
  page190_i105
#CELL
  pure_quanta q_capp *
  page190_i106
#CELL
  pure_quanta q_capp *
  page190_i107
#CELL
  pure_quanta q_cap *
  page190_i108
#CELL
  pure_quanta q_cap *
  page190_i109
#CELL
  pure_quanta q_cap *
  page190_i110
#ISCELL
  pure_quanta_power universal_gnd *
  page190_i111
#ISCELL
  pure_quanta_power universal_gnd *
  page190_i112
#CELL
  pure_quanta q_res *
  page190_i113
#CELL
  pure_quanta q_cap *
  page190_i114
#ISCELL
  pure_quanta_power vcc_core *
  page190_i115
#CELL
  pure_quanta q_cap *
  page190_i116
#ISCELL
  pure_quanta_power universal_gnd *
  page190_i117
#ISCELL
  pure_quanta_power universal_gnd *
  page190_i118
#CELL
  pure_quanta q_res *
  page190_i119
#CELL
  pure_quanta q_cap *
  page190_i120
#ISCELL
  pure_quanta_power vcc_core *
  page190_i121
#ISCELL
  standard offpage *
  page190_i122
#ISCELL
  pure_quanta_power universal_gnd *
  page190_i123
#CELL
  pure_quanta q_res *
  page190_i124
#CELL
  pure_quanta q_cap *
  page190_i125
#ISCELL
  pure_quanta_power universal_gnd *
  page190_i126
#CELL
  pure_quanta q_res *
  page190_i127
#CELL
  pure_quanta q_cap *
  page190_i128
#CELL
  pure_quanta q_res *
  page190_i129
#CELL
  pure_quanta q_cap *
  page190_i130
#CELL
  pure_quanta q_cap *
  page190_i131
#ISCELL
  standard offpage *
  page190_i132
#ISCELL
  pure_quanta_power universal_gnd *
  page190_i133
#CELL
  pure_quanta q_res *
  page190_i15
#CELL
  pure_quanta q_res *
  page190_i19
#ISCELL
  pure_quanta_power universal_gnd *
  page190_i2
#CELL
  pure_quanta q_res *
  page190_i22
#CELL
  pure_quanta q_cap *
  page190_i23
#CELL
  pure_quanta q_cap *
  page190_i24
#CELL
  pure_quanta q_cap *
  page190_i25
#CELL
  pure_quanta q_cap *
  page190_i26
#CELL
  pure_quanta q_cap *
  page190_i29
#ISCELL
  standard offpage *
  page190_i3
#ISCELL
  pure_quanta_power universal_gnd *
  page190_i31
#CELL
  pure_quanta q_inductor *
  page190_i34
#ISCELL
  pure_quanta_power vcc_core *
  page190_i35
#CELL
  pure_quanta q_cap *
  page190_i37
#ISCELL
  pure_quanta_power universal_gnd *
  page190_i38
#CELL
  pure_quanta q_cap *
  page190_i39
#CELL
  pure_quanta q_cap *
  page190_i4
#ISCELL
  pure_quanta_power vcc_core *
  page190_i40
#CELL
  pure_quanta q_inductor4p_14 *
  page190_i42
#CELL
  pure_quanta q_cap *
  page190_i43
#CELL
  pure_quanta isl99390frztr5935 *
  page190_i44
#ISCELL
  standard offpage *
  page190_i45
#ISCELL
  pure_quanta_power universal_gnd *
  page190_i46
#ISCELL
  standard offpage *
  page190_i47
#CELL
  pure_quanta q_cap *
  page190_i48
#ISCELL
  pure_quanta_power universal_gnd *
  page190_i49
#ISCELL
  pure_quanta_power universal_gnd *
  page190_i5
#ISCELL
  pure_quanta_power universal_gnd *
  page190_i50
#ISCELL
  standard offpage *
  page190_i51
#CELL
  pure_quanta q_res *
  page190_i52
#ISCELL
  standard offpage *
  page190_i55
#ISCELL
  pure_quanta_power universal_gnd *
  page190_i6
#CELL
  pure_quanta q_res *
  page190_i63
#CELL
  pure_quanta q_res *
  page190_i65
#CELL
  pure_quanta q_cap *
  page190_i66
#CELL
  pure_quanta q_cap *
  page190_i67
#CELL
  pure_quanta q_cap *
  page190_i68
#CELL
  pure_quanta q_cap *
  page190_i69
#ISCELL
  standard offpage *
  page190_i7
#CELL
  pure_quanta q_cap *
  page190_i70
#ISCELL
  pure_quanta_power universal_gnd *
  page190_i71
#ISCELL
  pure_quanta_power vcc_core *
  page190_i73
#CELL
  pure_quanta q_cap *
  page190_i79
#ISCELL
  pure_quanta_power universal_gnd *
  page190_i80
#CELL
  pure_quanta q_cap *
  page190_i81
#ISCELL
  pure_quanta_power vcc_core *
  page190_i82
#CELL
  pure_quanta q_inductor4p_14 *
  page190_i83
#CELL
  pure_quanta isl99390frztr5935 *
  page190_i84
#ISCELL
  standard offpage *
  page190_i86
#CELL
  pure_quanta q_capp *
  page190_i92
#CELL
  pure_quanta q_capp *
  page190_i94
